(kicad_pcb
	(version 20260206)
	(generator "pcbnew")
	(generator_version "10.0")
	(general
		(thickness 1.6)
		(legacy_teardrops no)
	)
	(paper "A4")
	(title_block
		(title "peb — Lightning_PEB_BRD.brd")
		(comment 1 "Lightning (Wiwynn / Facebook NVMe JBOF) / footprints 1442-1444 of 2563")
	)
	(layers
		(0 "F.Cu" signal "TOP")
		(4 "In1.Cu" signal "L2GND")
		(6 "In2.Cu" signal "L3")
		(8 "In3.Cu" signal "L4VCC")
		(10 "In4.Cu" signal "L5VCC")
		(12 "In5.Cu" signal "L6")
		(14 "In6.Cu" signal "L7GND")
		(2 "B.Cu" signal "BOTTOM")
		(9 "F.Adhes" user "F.Adhesive")
		(11 "B.Adhes" user "B.Adhesive")
		(13 "F.Paste" user "Package Geometry/Pastemask Top")
		(15 "B.Paste" user "Package Geometry/Pastemask Bottom")
		(5 "F.SilkS" user "Ref Des/Silkscreen Top")
		(7 "B.SilkS" user "Ref Des/Silkscreen Bottom")
		(1 "F.Mask" user "Board Geometry/Soldermask Top")
		(3 "B.Mask" user "Board Geometry/Soldermask Bottom")
		(17 "Dwgs.User" user "User.Drawings")
		(19 "Cmts.User" user "User.Comments")
		(21 "Eco1.User" user "User.Eco1")
		(23 "Eco2.User" user "User.Eco2")
		(25 "Edge.Cuts" user "Board Geometry/Outline")
		(27 "Margin" user)
		(31 "F.CrtYd" user "Package Geometry/Place Bound Top")
		(29 "B.CrtYd" user "Package Geometry/Place Bound Bottom")
		(35 "F.Fab" user "Ref Des/Assembly Top")
		(33 "B.Fab" user "Ref Des/Assembly Bottom")
	)
	(footprint ""
		(layer "F.Cu")
		(at 166.497 -90.8304 90)
		(property "Reference" "R92"
			(at 0 0 90)
			(layer "F.SilkS")
			(hide yes)
			(effects
				(font
					(size 1.27 1.27)
				)
			)
		)
		(property "Value" "1R3F-GP"
			(at -0.0254 -2.5146 90)
			(unlocked yes)
			(layer "F.Fab")
			(hide yes)
			(effects
				(font
					(size 1.016 1.016)
					(thickness 0.1524)
				)
			)
		)
		(property "Device Type" "R603H22"
			(at -0.0254 -4.0386 90)
			(unlocked yes)
			(layer "F.Fab")
			(hide yes)
			(effects
				(font
					(size 1.016 1.016)
					(thickness 0.1524)
				)
			)
		)
		(duplicate_pad_numbers_are_jumpers no)
		(fp_line
			(start 0.2032 0)
			(end 0.4826 0)
			(stroke
				(width 0.2032)
				(type default)
			)
			(layer "F.SilkS")
		)
		(fp_line
			(start -0.4826 0)
			(end -0.2032 0)
			(stroke
				(width 0.2032)
				(type default)
			)
			(layer "F.SilkS")
		)
		(fp_rect
			(start -0.5842 1.3335)
			(end 0.5842 -1.3335)
			(stroke
				(width 0)
				(type default)
			)
			(fill no)
			(layer "F.CrtYd")
		)
		(fp_rect
			(start -0.5842 1.3335)
			(end 0.5842 -1.3335)
			(stroke
				(width 0)
				(type default)
			)
			(fill no)
			(layer "F.Fab")
		)
		(pad "1" smd custom
			(at 0 -0.762 90)
			(size 0.2159 0.2159)
			(layers "F.Cu" "F.Mask" "F.Paste")
			(net "P1V8_CLKGEN_A")
			(options
				(clearance outline)
				(anchor circle)
			)
			(primitives
				(gr_poly
					(pts
						(arc
							(start -0.3302 -0.4318)
							(mid -0.402042 -0.402042)
							(end -0.4318 -0.3302)
						)
						(arc
							(start -0.4318 0.3302)
							(mid -0.402042 0.402042)
							(end -0.3302 0.4318)
						)
						(arc
							(start 0.3302 0.4318)
							(mid 0.402042 0.402042)
							(end 0.4318 0.3302)
						)
						(arc
							(start 0.4318 -0.3302)
							(mid 0.402042 -0.402042)
							(end 0.3302 -0.4318)
						)
					)
					(width 0)
					(fill yes)
				)
			)
		)
		(pad "2" smd custom
			(at 0 0.762 90)
			(size 0.2159 0.2159)
			(layers "F.Cu" "F.Mask" "F.Paste")
			(net "P1V8_CLKGEN")
			(options
				(clearance outline)
				(anchor circle)
			)
			(primitives
				(gr_poly
					(pts
						(arc
							(start -0.3302 -0.4318)
							(mid -0.402042 -0.402042)
							(end -0.4318 -0.3302)
						)
						(arc
							(start -0.4318 0.3302)
							(mid -0.402042 0.402042)
							(end -0.3302 0.4318)
						)
						(arc
							(start 0.3302 0.4318)
							(mid 0.402042 0.402042)
							(end 0.4318 0.3302)
						)
						(arc
							(start 0.4318 -0.3302)
							(mid 0.402042 -0.402042)
							(end 0.3302 -0.4318)
						)
					)
					(width 0)
					(fill yes)
				)
			)
		)
	)
	(footprint ""
		(layer "F.Cu")
		(at 239.720374 -6.444996 90)
		(property "Reference" "C319"
			(at 0 0 90)
			(layer "F.SilkS")
			(hide yes)
			(effects
				(font
					(size 1.27 1.27)
				)
			)
		)
		(property "Value" "SCD1U16V2KX-3GP"
			(at 1.1811 -2.7051 90)
			(unlocked yes)
			(layer "F.Fab")
			(hide yes)
			(effects
				(font
					(size 1.016 1.016)
					(thickness 0.1524)
				)
			)
		)
		(property "Device Type" "C402H22"
			(at 1.1811 -4.2291 90)
			(unlocked yes)
			(layer "F.Fab")
			(hide yes)
			(effects
				(font
					(size 1.016 1.016)
					(thickness 0.1524)
				)
			)
		)
		(duplicate_pad_numbers_are_jumpers no)
		(fp_rect
			(start -0.4318 0.9525)
			(end 0.4318 -0.9525)
			(stroke
				(width 0)
				(type default)
			)
			(fill no)
			(layer "F.CrtYd")
		)
		(fp_rect
			(start -0.4318 0.9525)
			(end 0.4318 -0.9525)
			(stroke
				(width 0)
				(type default)
			)
			(fill no)
			(layer "F.Fab")
		)
		(pad "1" smd custom
			(at 0 -0.4445 90)
			(size 0.1524 0.1524)
			(layers "F.Cu" "F.Mask" "F.Paste")
			(net "UART_COUNT")
			(options
				(clearance outline)
				(anchor circle)
			)
			(primitives
				(gr_poly
					(pts
						(arc
							(start 0.3048 -0.2032)
							(mid 0.275042 -0.275042)
							(end 0.2032 -0.3048)
						)
						(arc
							(start -0.2032 -0.3048)
							(mid -0.275042 -0.275042)
							(end -0.3048 -0.2032)
						)
						(arc
							(start -0.3048 0.2032)
							(mid -0.275042 0.275042)
							(end -0.2032 0.3048)
						)
						(arc
							(start 0.2032 0.3048)
							(mid 0.275042 0.275042)
							(end 0.3048 0.2032)
						)
					)
					(width 0)
					(fill yes)
				)
			)
		)
		(pad "2" smd custom
			(at 0 0.4445 90)
			(size 0.1524 0.1524)
			(layers "F.Cu" "F.Mask" "F.Paste")
			(net "GND")
			(options
				(clearance outline)
				(anchor circle)
			)
			(primitives
				(gr_poly
					(pts
						(arc
							(start 0.3048 -0.2032)
							(mid 0.275042 -0.275042)
							(end 0.2032 -0.3048)
						)
						(arc
							(start -0.2032 -0.3048)
							(mid -0.275042 -0.275042)
							(end -0.3048 -0.2032)
						)
						(arc
							(start -0.3048 0.2032)
							(mid -0.275042 0.275042)
							(end -0.2032 0.3048)
						)
						(arc
							(start 0.2032 0.3048)
							(mid 0.275042 0.275042)
							(end 0.3048 0.2032)
						)
					)
					(width 0)
					(fill yes)
				)
			)
		)
	)
	(footprint ""
		(layer "F.Cu")
		(at 18.415 -130.683 -90)
		(property "Reference" "R353"
			(at 0 0 270)
			(layer "F.SilkS")
			(hide yes)
			(effects
				(font
					(size 1.27 1.27)
				)
			)
		)
		(property "Value" "3K3R2F-2-GP"
			(at 0.064008 -3.993896 270)
			(unlocked yes)
			(layer "F.Fab")
			(hide yes)
			(effects
				(font
					(size 1.016 1.016)
					(thickness 0.1524)
				)
			)
		)
		(property "Device Type" "R402H16"
			(at 0.064008 -5.517896 270)
			(unlocked yes)
			(layer "F.Fab")
			(hide yes)
			(effects
				(font
					(size 1.016 1.016)
					(thickness 0.1524)
				)
			)
		)
		(duplicate_pad_numbers_are_jumpers no)
		(fp_line
			(start -0.508 -0.9398)
			(end -0.508 0.9398)
			(stroke
				(width 0.1524)
				(type default)
			)
			(layer "F.SilkS")
		)
		(fp_line
			(start 0.508 -0.9398)
			(end -0.508 -0.9398)
			(stroke
				(width 0.1524)
				(type default)
			)
			(layer "F.SilkS")
		)
		(fp_rect
			(start -0.508 0.9398)
			(end 0.508 -0.9398)
			(stroke
				(width 0)
				(type default)
			)
			(fill no)
			(layer "F.CrtYd")
		)
		(fp_rect
			(start -0.508 0.9398)
			(end 0.508 -0.9398)
			(stroke
				(width 0)
				(type default)
			)
			(fill no)
			(layer "F.Fab")
		)
		(pad "1" smd custom
			(at 0 -0.4445 270)
			(size 0.1397 0.1397)
			(layers "F.Cu" "F.Mask" "F.Paste")
			(net "P3V3_STBY")
			(options
				(clearance outline)
				(anchor circle)
			)
			(primitives
				(gr_poly
					(pts
						(arc
							(start -0.1778 -0.2794)
							(mid -0.249642 -0.249642)
							(end -0.2794 -0.1778)
						)
						(arc
							(start -0.2794 0.1778)
							(mid -0.249642 0.249642)
							(end -0.1778 0.2794)
						)
						(arc
							(start 0.1778 0.2794)
							(mid 0.249642 0.249642)
							(end 0.2794 0.1778)
						)
						(arc
							(start 0.2794 -0.1778)
							(mid 0.249642 -0.249642)
							(end 0.1778 -0.2794)
						)
					)
					(width 0)
					(fill yes)
				)
			)
		)
		(pad "2" smd custom
			(at 0 0.4445 270)
			(size 0.1397 0.1397)
			(layers "F.Cu" "F.Mask" "F.Paste")
			(net "ROMA19")
			(options
				(clearance outline)
				(anchor circle)
			)
			(primitives
				(gr_poly
					(pts
						(arc
							(start -0.1778 -0.2794)
							(mid -0.249642 -0.249642)
							(end -0.2794 -0.1778)
						)
						(arc
							(start -0.2794 0.1778)
							(mid -0.249642 0.249642)
							(end -0.1778 0.2794)
						)
						(arc
							(start 0.1778 0.2794)
							(mid 0.249642 0.249642)
							(end 0.2794 0.1778)
						)
						(arc
							(start 0.2794 -0.1778)
							(mid 0.249642 -0.249642)
							(end 0.1778 -0.2794)
						)
					)
					(width 0)
					(fill yes)
				)
			)
		)
	)
)
